(kicad_pcb
	(version 20260206)
	(generator "pcbnew")
	(generator_version "10.0")
	(general
		(thickness 1.6)
		(legacy_teardrops no)
	)
	(paper "A4")
	(title_block
		(title "baseboard — 13948-1b.1110WZS1818.brd")
		(comment 1 "Honey Badger (Wiwynn) / footprints 560-566 of 2523")
	)
	(layers
		(0 "F.Cu" signal "TOP")
		(4 "In1.Cu" signal "L2GND")
		(6 "In2.Cu" signal "L3")
		(8 "In3.Cu" signal "L4VCC")
		(10 "In4.Cu" signal "L5VCC")
		(12 "In5.Cu" signal "L6")
		(14 "In6.Cu" signal "L7GND")
		(2 "B.Cu" signal "BOTTOM")
		(9 "F.Adhes" user "F.Adhesive")
		(11 "B.Adhes" user "B.Adhesive")
		(13 "F.Paste" user "Package Geometry/Pastemask Top")
		(15 "B.Paste" user "Package Geometry/Pastemask Bottom")
		(5 "F.SilkS" user "Ref Des/Silkscreen Top")
		(7 "B.SilkS" user "Ref Des/Silkscreen Bottom")
		(1 "F.Mask" user "Board Geometry/Soldermask Top")
		(3 "B.Mask" user "Board Geometry/Soldermask Bottom")
		(17 "Dwgs.User" user "User.Drawings")
		(19 "Cmts.User" user "User.Comments")
		(21 "Eco1.User" user "User.Eco1")
		(23 "Eco2.User" user "User.Eco2")
		(25 "Edge.Cuts" user "Board Geometry/Outline")
		(27 "Margin" user)
		(31 "F.CrtYd" user "Package Geometry/Place Bound Top")
		(29 "B.CrtYd" user "Package Geometry/Place Bound Bottom")
		(35 "F.Fab" user "Ref Des/Assembly Top")
		(33 "B.Fab" user "Ref Des/Assembly Bottom")
	)
	(footprint ""
		(layer "F.Cu")
		(at 191.697864 -28.520136 90)
		(property "Reference" "R377"
			(at 0 0 90)
			(layer "F.SilkS")
			(hide yes)
			(effects
				(font
					(size 1.27 1.27)
				)
			)
		)
		(property "Value" "33R2J-2-GP"
			(at 0.064008 -3.993896 90)
			(unlocked yes)
			(layer "F.Fab")
			(hide yes)
			(effects
				(font
					(size 1.016 1.016)
					(thickness 0.1524)
				)
			)
		)
		(property "Device Type" "R402H16"
			(at 0.064008 -5.517896 90)
			(unlocked yes)
			(layer "F.Fab")
			(hide yes)
			(effects
				(font
					(size 1.016 1.016)
					(thickness 0.1524)
				)
			)
		)
		(duplicate_pad_numbers_are_jumpers no)
		(fp_line
			(start 0.508 -0.9398)
			(end -0.508 -0.9398)
			(stroke
				(width 0.1524)
				(type default)
			)
			(layer "F.SilkS")
		)
		(fp_line
			(start -0.508 -0.9398)
			(end -0.508 0.9398)
			(stroke
				(width 0.1524)
				(type default)
			)
			(layer "F.SilkS")
		)
		(fp_rect
			(start -0.508 0.9398)
			(end 0.508 -0.9398)
			(stroke
				(width 0)
				(type default)
			)
			(fill no)
			(layer "F.CrtYd")
		)
		(fp_rect
			(start -0.508 0.9398)
			(end 0.508 -0.9398)
			(stroke
				(width 0)
				(type default)
			)
			(fill no)
			(layer "F.Fab")
		)
		(pad "1" smd custom
			(at 0 -0.4445 90)
			(size 0.1397 0.1397)
			(layers "F.Cu" "F.Mask" "F.Paste")
			(net "RMII_BMC_RX_ER_R")
			(options
				(clearance outline)
				(anchor circle)
			)
			(primitives
				(gr_poly
					(pts
						(arc
							(start -0.1778 -0.2794)
							(mid -0.249642 -0.249642)
							(end -0.2794 -0.1778)
						)
						(arc
							(start -0.2794 0.1778)
							(mid -0.249642 0.249642)
							(end -0.1778 0.2794)
						)
						(arc
							(start 0.1778 0.2794)
							(mid 0.249642 0.249642)
							(end 0.2794 0.1778)
						)
						(arc
							(start 0.2794 -0.1778)
							(mid 0.249642 -0.249642)
							(end 0.1778 -0.2794)
						)
					)
					(width 0)
					(fill yes)
				)
			)
		)
		(pad "2" smd custom
			(at 0 0.4445 90)
			(size 0.1397 0.1397)
			(layers "F.Cu" "F.Mask" "F.Paste")
			(net "RMII_BMC_RX_ER")
			(options
				(clearance outline)
				(anchor circle)
			)
			(primitives
				(gr_poly
					(pts
						(arc
							(start -0.1778 -0.2794)
							(mid -0.249642 -0.249642)
							(end -0.2794 -0.1778)
						)
						(arc
							(start -0.2794 0.1778)
							(mid -0.249642 0.249642)
							(end -0.1778 0.2794)
						)
						(arc
							(start 0.1778 0.2794)
							(mid 0.249642 0.249642)
							(end 0.2794 0.1778)
						)
						(arc
							(start 0.2794 -0.1778)
							(mid 0.249642 -0.249642)
							(end 0.1778 -0.2794)
						)
					)
					(width 0)
					(fill yes)
				)
			)
		)
	)
	(footprint ""
		(layer "F.Cu")
		(at 342.256872 -115.515136)
		(property "Reference" "PR6"
			(at 0 0 0)
			(layer "F.SilkS")
			(hide yes)
			(effects
				(font
					(size 1.27 1.27)
				)
			)
		)
		(property "Value" "10KR2F-2-GP"
			(at 0.064008 -3.993896 0)
			(unlocked yes)
			(layer "F.Fab")
			(hide yes)
			(effects
				(font
					(size 1.016 1.016)
					(thickness 0.1524)
				)
			)
		)
		(property "Device Type" "R402H16"
			(at 0.064008 -5.517896 0)
			(unlocked yes)
			(layer "F.Fab")
			(hide yes)
			(effects
				(font
					(size 1.016 1.016)
					(thickness 0.1524)
				)
			)
		)
		(duplicate_pad_numbers_are_jumpers no)
		(fp_line
			(start -0.508 -0.9398)
			(end -0.508 0.9398)
			(stroke
				(width 0.1524)
				(type default)
			)
			(layer "F.SilkS")
		)
		(fp_line
			(start 0.508 -0.9398)
			(end -0.508 -0.9398)
			(stroke
				(width 0.1524)
				(type default)
			)
			(layer "F.SilkS")
		)
		(fp_rect
			(start -0.508 0.9398)
			(end 0.508 -0.9398)
			(stroke
				(width 0)
				(type default)
			)
			(fill no)
			(layer "F.CrtYd")
		)
		(fp_rect
			(start -0.508 0.9398)
			(end 0.508 -0.9398)
			(stroke
				(width 0)
				(type default)
			)
			(fill no)
			(layer "F.Fab")
		)
		(pad "1" smd custom
			(at 0 -0.4445)
			(size 0.1397 0.1397)
			(layers "F.Cu" "F.Mask" "F.Paste")
			(net "AGND_P5V_STBY")
			(options
				(clearance outline)
				(anchor circle)
			)
			(primitives
				(gr_poly
					(pts
						(arc
							(start -0.1778 -0.2794)
							(mid -0.249642 -0.249642)
							(end -0.2794 -0.1778)
						)
						(arc
							(start -0.2794 0.1778)
							(mid -0.249642 0.249642)
							(end -0.1778 0.2794)
						)
						(arc
							(start 0.1778 0.2794)
							(mid 0.249642 0.249642)
							(end 0.2794 0.1778)
						)
						(arc
							(start 0.2794 -0.1778)
							(mid 0.249642 -0.249642)
							(end 0.1778 -0.2794)
						)
					)
					(width 0)
					(fill yes)
				)
			)
		)
		(pad "2" smd custom
			(at 0 0.4445)
			(size 0.1397 0.1397)
			(layers "F.Cu" "F.Mask" "F.Paste")
			(net "P5V_STBY_VFB")
			(options
				(clearance outline)
				(anchor circle)
			)
			(primitives
				(gr_poly
					(pts
						(arc
							(start -0.1778 -0.2794)
							(mid -0.249642 -0.249642)
							(end -0.2794 -0.1778)
						)
						(arc
							(start -0.2794 0.1778)
							(mid -0.249642 0.249642)
							(end -0.1778 0.2794)
						)
						(arc
							(start 0.1778 0.2794)
							(mid 0.249642 0.249642)
							(end 0.2794 0.1778)
						)
						(arc
							(start 0.2794 -0.1778)
							(mid 0.249642 -0.249642)
							(end 0.1778 -0.2794)
						)
					)
					(width 0)
					(fill yes)
				)
			)
		)
	)
	(footprint ""
		(layer "F.Cu")
		(at 111.89716 -27.94 -90)
		(property "Reference" "SR683"
			(at 0 0 270)
			(layer "F.SilkS")
			(hide yes)
			(effects
				(font
					(size 1.27 1.27)
				)
			)
		)
		(property "Value" "10KR2F-2-GP"
			(at 0.064008 -3.993896 270)
			(unlocked yes)
			(layer "F.Fab")
			(hide yes)
			(effects
				(font
					(size 1.016 1.016)
					(thickness 0.1524)
				)
			)
		)
		(property "Device Type" "R402H16"
			(at 0.064008 -5.517896 270)
			(unlocked yes)
			(layer "F.Fab")
			(hide yes)
			(effects
				(font
					(size 1.016 1.016)
					(thickness 0.1524)
				)
			)
		)
		(duplicate_pad_numbers_are_jumpers no)
		(fp_line
			(start -0.508 -0.9398)
			(end -0.508 0.9398)
			(stroke
				(width 0.1524)
				(type default)
			)
			(layer "F.SilkS")
		)
		(fp_line
			(start 0.508 -0.9398)
			(end -0.508 -0.9398)
			(stroke
				(width 0.1524)
				(type default)
			)
			(layer "F.SilkS")
		)
		(fp_rect
			(start -0.508 0.9398)
			(end 0.508 -0.9398)
			(stroke
				(width 0)
				(type default)
			)
			(fill no)
			(layer "F.CrtYd")
		)
		(fp_rect
			(start -0.508 0.9398)
			(end 0.508 -0.9398)
			(stroke
				(width 0)
				(type default)
			)
			(fill no)
			(layer "F.Fab")
		)
		(pad "1" smd custom
			(at 0 -0.4445 270)
			(size 0.1397 0.1397)
			(layers "F.Cu" "F.Mask" "F.Paste")
			(net "SYS_DBMODE3")
			(options
				(clearance outline)
				(anchor circle)
			)
			(primitives
				(gr_poly
					(pts
						(arc
							(start -0.1778 -0.2794)
							(mid -0.249642 -0.249642)
							(end -0.2794 -0.1778)
						)
						(arc
							(start -0.2794 0.1778)
							(mid -0.249642 0.249642)
							(end -0.1778 0.2794)
						)
						(arc
							(start 0.1778 0.2794)
							(mid 0.249642 0.249642)
							(end 0.2794 0.1778)
						)
						(arc
							(start 0.2794 -0.1778)
							(mid 0.249642 -0.249642)
							(end 0.1778 -0.2794)
						)
					)
					(width 0)
					(fill yes)
				)
			)
		)
		(pad "2" smd custom
			(at 0 0.4445 270)
			(size 0.1397 0.1397)
			(layers "F.Cu" "F.Mask" "F.Paste")
			(net "GND")
			(options
				(clearance outline)
				(anchor circle)
			)
			(primitives
				(gr_poly
					(pts
						(arc
							(start -0.1778 -0.2794)
							(mid -0.249642 -0.249642)
							(end -0.2794 -0.1778)
						)
						(arc
							(start -0.2794 0.1778)
							(mid -0.249642 0.249642)
							(end -0.1778 0.2794)
						)
						(arc
							(start 0.1778 0.2794)
							(mid 0.249642 0.249642)
							(end 0.2794 0.1778)
						)
						(arc
							(start 0.2794 -0.1778)
							(mid 0.249642 -0.249642)
							(end 0.1778 -0.2794)
						)
					)
					(width 0)
					(fill yes)
				)
			)
		)
	)
	(footprint ""
		(layer "F.Cu")
		(at 80.626966 -84.963 90)
		(property "Reference" "SR830"
			(at 0 0 90)
			(layer "F.SilkS")
			(hide yes)
			(effects
				(font
					(size 1.27 1.27)
				)
			)
		)
		(property "Value" "10R2F-L-GP"
			(at 0.064008 -3.993896 90)
			(unlocked yes)
			(layer "F.Fab")
			(hide yes)
			(effects
				(font
					(size 1.016 1.016)
					(thickness 0.1524)
				)
			)
		)
		(property "Device Type" "R402H14"
			(at 0.064008 -5.517896 90)
			(unlocked yes)
			(layer "F.Fab")
			(hide yes)
			(effects
				(font
					(size 1.016 1.016)
					(thickness 0.1524)
				)
			)
		)
		(duplicate_pad_numbers_are_jumpers no)
		(fp_line
			(start 0.508 -0.9398)
			(end -0.508 -0.9398)
			(stroke
				(width 0.1524)
				(type default)
			)
			(layer "F.SilkS")
		)
		(fp_line
			(start -0.508 -0.9398)
			(end -0.508 0.9398)
			(stroke
				(width 0.1524)
				(type default)
			)
			(layer "F.SilkS")
		)
		(fp_rect
			(start -0.508 0.9398)
			(end 0.508 -0.9398)
			(stroke
				(width 0)
				(type default)
			)
			(fill no)
			(layer "F.CrtYd")
		)
		(fp_rect
			(start -0.508 0.9398)
			(end 0.508 -0.9398)
			(stroke
				(width 0)
				(type default)
			)
			(fill no)
			(layer "F.Fab")
		)
		(pad "1" smd custom
			(at 0 -0.4445 90)
			(size 0.1397 0.1397)
			(layers "F.Cu" "F.Mask" "F.Paste")
			(net "P1V8_E")
			(options
				(clearance outline)
				(anchor circle)
			)
			(primitives
				(gr_poly
					(pts
						(arc
							(start -0.1778 -0.2794)
							(mid -0.249642 -0.249642)
							(end -0.2794 -0.1778)
						)
						(arc
							(start -0.2794 0.1778)
							(mid -0.249642 0.249642)
							(end -0.1778 0.2794)
						)
						(arc
							(start 0.1778 0.2794)
							(mid 0.249642 0.249642)
							(end 0.2794 0.1778)
						)
						(arc
							(start 0.2794 -0.1778)
							(mid 0.249642 -0.249642)
							(end 0.1778 -0.2794)
						)
					)
					(width 0)
					(fill yes)
				)
			)
		)
		(pad "2" smd custom
			(at 0 0.4445 90)
			(size 0.1397 0.1397)
			(layers "F.Cu" "F.Mask" "F.Paste")
			(net "PLLDDR_VDDA18")
			(options
				(clearance outline)
				(anchor circle)
			)
			(primitives
				(gr_poly
					(pts
						(arc
							(start -0.1778 -0.2794)
							(mid -0.249642 -0.249642)
							(end -0.2794 -0.1778)
						)
						(arc
							(start -0.2794 0.1778)
							(mid -0.249642 0.249642)
							(end -0.1778 0.2794)
						)
						(arc
							(start 0.1778 0.2794)
							(mid 0.249642 0.249642)
							(end 0.2794 0.1778)
						)
						(arc
							(start 0.2794 -0.1778)
							(mid 0.249642 -0.249642)
							(end 0.1778 -0.2794)
						)
					)
					(width 0)
					(fill yes)
				)
			)
		)
	)
	(footprint ""
		(layer "F.Cu")
		(at 258.699 -71.501 -90)
		(property "Reference" "C310"
			(at 0 0 270)
			(layer "F.SilkS")
			(hide yes)
			(effects
				(font
					(size 1.27 1.27)
				)
			)
		)
		(property "Value" "SCD1U25V2KX-2-GP"
			(at 1.1811 -2.7051 270)
			(unlocked yes)
			(layer "F.Fab")
			(hide yes)
			(effects
				(font
					(size 1.016 1.016)
					(thickness 0.1524)
				)
			)
		)
		(property "Device Type" "C402H22"
			(at 1.1811 -4.2291 270)
			(unlocked yes)
			(layer "F.Fab")
			(hide yes)
			(effects
				(font
					(size 1.016 1.016)
					(thickness 0.1524)
				)
			)
		)
		(duplicate_pad_numbers_are_jumpers no)
		(fp_rect
			(start -0.4318 0.9525)
			(end 0.4318 -0.9525)
			(stroke
				(width 0)
				(type default)
			)
			(fill no)
			(layer "F.CrtYd")
		)
		(fp_rect
			(start -0.4318 0.9525)
			(end 0.4318 -0.9525)
			(stroke
				(width 0)
				(type default)
			)
			(fill no)
			(layer "F.Fab")
		)
		(pad "1" smd custom
			(at 0 -0.4445 270)
			(size 0.1524 0.1524)
			(layers "F.Cu" "F.Mask" "F.Paste")
			(net "P12V_MSB")
			(options
				(clearance outline)
				(anchor circle)
			)
			(primitives
				(gr_poly
					(pts
						(arc
							(start 0.3048 -0.2032)
							(mid 0.275042 -0.275042)
							(end 0.2032 -0.3048)
						)
						(arc
							(start -0.2032 -0.3048)
							(mid -0.275042 -0.275042)
							(end -0.3048 -0.2032)
						)
						(arc
							(start -0.3048 0.2032)
							(mid -0.275042 0.275042)
							(end -0.2032 0.3048)
						)
						(arc
							(start 0.2032 0.3048)
							(mid 0.275042 0.275042)
							(end 0.3048 0.2032)
						)
					)
					(width 0)
					(fill yes)
				)
			)
		)
		(pad "2" smd custom
			(at 0 0.4445 270)
			(size 0.1524 0.1524)
			(layers "F.Cu" "F.Mask" "F.Paste")
			(net "GND")
			(options
				(clearance outline)
				(anchor circle)
			)
			(primitives
				(gr_poly
					(pts
						(arc
							(start 0.3048 -0.2032)
							(mid 0.275042 -0.275042)
							(end 0.2032 -0.3048)
						)
						(arc
							(start -0.2032 -0.3048)
							(mid -0.275042 -0.275042)
							(end -0.3048 -0.2032)
						)
						(arc
							(start -0.3048 0.2032)
							(mid -0.275042 0.275042)
							(end -0.2032 0.3048)
						)
						(arc
							(start 0.2032 0.3048)
							(mid 0.275042 0.275042)
							(end 0.3048 0.2032)
						)
					)
					(width 0)
					(fill yes)
				)
			)
		)
	)
	(footprint ""
		(layer "F.Cu")
		(at 219.828872 -179.904136 180)
		(property "Reference" "R493"
			(at 0 0 180)
			(layer "F.SilkS")
			(hide yes)
			(effects
				(font
					(size 1.27 1.27)
				)
			)
		)
		(property "Value" "4K7R2F-GP"
			(at 0.064008 -3.993896 180)
			(unlocked yes)
			(layer "F.Fab")
			(hide yes)
			(effects
				(font
					(size 1.016 1.016)
					(thickness 0.1524)
				)
			)
		)
		(property "Device Type" "R402H16"
			(at 0.064008 -5.517896 180)
			(unlocked yes)
			(layer "F.Fab")
			(hide yes)
			(effects
				(font
					(size 1.016 1.016)
					(thickness 0.1524)
				)
			)
		)
		(duplicate_pad_numbers_are_jumpers no)
		(fp_line
			(start 0.508 -0.9398)
			(end -0.508 -0.9398)
			(stroke
				(width 0.1524)
				(type default)
			)
			(layer "F.SilkS")
		)
		(fp_line
			(start -0.508 -0.9398)
			(end -0.508 0.9398)
			(stroke
				(width 0.1524)
				(type default)
			)
			(layer "F.SilkS")
		)
		(fp_rect
			(start -0.508 0.9398)
			(end 0.508 -0.9398)
			(stroke
				(width 0)
				(type default)
			)
			(fill no)
			(layer "F.CrtYd")
		)
		(fp_rect
			(start -0.508 0.9398)
			(end 0.508 -0.9398)
			(stroke
				(width 0)
				(type default)
			)
			(fill no)
			(layer "F.Fab")
		)
		(pad "1" smd custom
			(at 0 -0.4445 180)
			(size 0.1397 0.1397)
			(layers "F.Cu" "F.Mask" "F.Paste")
			(net "DIVIDER 1_IN_EXP")
			(options
				(clearance outline)
				(anchor circle)
			)
			(primitives
				(gr_poly
					(pts
						(arc
							(start -0.1778 -0.2794)
							(mid -0.249642 -0.249642)
							(end -0.2794 -0.1778)
						)
						(arc
							(start -0.2794 0.1778)
							(mid -0.249642 0.249642)
							(end -0.1778 0.2794)
						)
						(arc
							(start 0.1778 0.2794)
							(mid 0.249642 0.249642)
							(end 0.2794 0.1778)
						)
						(arc
							(start 0.2794 -0.1778)
							(mid 0.249642 -0.249642)
							(end 0.1778 -0.2794)
						)
					)
					(width 0)
					(fill yes)
				)
			)
		)
		(pad "2" smd custom
			(at 0 0.4445 180)
			(size 0.1397 0.1397)
			(layers "F.Cu" "F.Mask" "F.Paste")
			(net "DIVIDER 2_IN_EXP")
			(options
				(clearance outline)
				(anchor circle)
			)
			(primitives
				(gr_poly
					(pts
						(arc
							(start -0.1778 -0.2794)
							(mid -0.249642 -0.249642)
							(end -0.2794 -0.1778)
						)
						(arc
							(start -0.2794 0.1778)
							(mid -0.249642 0.249642)
							(end -0.1778 0.2794)
						)
						(arc
							(start 0.1778 0.2794)
							(mid 0.249642 0.249642)
							(end 0.2794 0.1778)
						)
						(arc
							(start 0.2794 -0.1778)
							(mid 0.249642 -0.249642)
							(end 0.1778 -0.2794)
						)
					)
					(width 0)
					(fill yes)
				)
			)
		)
	)
	(footprint ""
		(layer "F.Cu")
		(at 152.247092 -95.914464 -90)
		(property "Reference" "SL19"
			(at 0 0 270)
			(layer "F.SilkS")
			(hide yes)
			(effects
				(font
					(size 1.27 1.27)
				)
			)
		)
		(property "Value" "MPZ2012S300AT-GP"
			(at 0 -4.2418 270)
			(unlocked yes)
			(layer "F.Fab")
			(hide yes)
			(effects
				(font
					(size 1.016 1.016)
					(thickness 0.1524)
				)
			)
		)
		(property "Device Type" "L805H42"
			(at 0 -5.7912 270)
			(unlocked yes)
			(layer "F.Fab")
			(hide yes)
			(effects
				(font
					(size 1.016 1.016)
					(thickness 0.1524)
				)
			)
		)
		(duplicate_pad_numbers_are_jumpers no)
		(fp_line
			(start -0.889 1.7018)
			(end -0.889 -1.7018)
			(stroke
				(width 0.1524)
				(type default)
			)
			(layer "F.SilkS")
		)
		(fp_line
			(start 0.889 1.7018)
			(end -0.889 1.7018)
			(stroke
				(width 0.1524)
				(type default)
			)
			(layer "F.SilkS")
		)
		(fp_line
			(start -0.889 -1.7018)
			(end 0.889 -1.7018)
			(stroke
				(width 0.1524)
				(type default)
			)
			(layer "F.SilkS")
		)
		(fp_line
			(start 0.889 -1.7018)
			(end 0.889 1.7018)
			(stroke
				(width 0.1524)
				(type default)
			)
			(layer "F.SilkS")
		)
		(fp_rect
			(start -0.9652 1.778)
			(end 0.9652 -1.778)
			(stroke
				(width 0)
				(type default)
			)
			(fill no)
			(layer "F.CrtYd")
		)
		(fp_rect
			(start -0.9652 1.778)
			(end 0.9652 -1.778)
			(stroke
				(width 0)
				(type default)
			)
			(fill no)
			(layer "F.Fab")
		)
		(pad "1" smd rect
			(at 0 -0.9652 270)
			(size 1.397 1.143)
			(layers "F.Cu" "F.Mask" "F.Paste")
			(net "P0V9_E")
		)
		(pad "2" smd rect
			(at 0 0.9652 270)
			(size 1.397 1.143)
			(layers "F.Cu" "F.Mask" "F.Paste")
			(net "GB_VDDA")
		)
	)
)
